FILE_TYPE = MULTI_PHYS_TABLE;
PART 'CONN72_G97614002_A'
{=================================================================================================================================================================================}
:PACK_TYPE | MATERIAL | PART_NUMBER     = EnvComp | PART_NUMBER  | JEDEC_TYPE        | DESCRIPTION                                 | CLASS |  HEIGHT    | COMPONENT_TYPE | LEAD_LENGTH | SPEED_URL | Status |RPL| AML | Bus_Unit | Days ;
{=================================================================================================================================================================================}
'CP'       | 'CONN'   | 'G97614-002'(!) = 'YES;YES;CNC;CNC;ok;VLD' | 'G97614-002' |'CONN72_G97614002' | '(SYM_1)CONN,MISC,72P,CONNECTOR,MINISAS HD' | 'IO'  | '0.550 IN' | 'PRESSFIT'     | '0.061'     | 'http://speed.intel.com:8081/speed/module/pdm/item/pdm_item_detail_direct.asp?item_cde=G97614-002&item_rev=01&url_param=unused' | 'Design' | 'NO' | '1' | 'SMO_BOARDS' | '???' 
'CP'       | 'EMPTY'  | 'G97614-002'(!) = 'YES;YES;CNC;CNC;ok;VLD' | 'G97614-002' |'CONN72_G97614002' | '(SYM_1)CONN,MISC,72P,CONNECTOR,MINISAS HD' | 'IO'  | '0.550 IN' | 'PRESSFIT'     | '0.061'     | 'http://speed.intel.com:8081/speed/module/pdm/item/pdm_item_detail_direct.asp?item_cde=G97614-002&item_rev=01&url_param=unused' | 'Design' | 'NO' | '1' | 'SMO_BOARDS' | '???' 
'BP'       | 'CONN'   | 'G97614-002'(!) = 'YES;YES;CNC;CNC;ok;VLD' | 'G97614-002' |'CONN72_G97614002' | '(SYM_2)CONN,MISC,72P,CONNECTOR,MINISAS HD' | 'IO'  | '0.550 IN' | 'PRESSFIT'     | '0.061'     | 'http://speed.intel.com:8081/speed/module/pdm/item/pdm_item_detail_direct.asp?item_cde=G97614-002&item_rev=01&url_param=unused' | 'Design' | 'NO' | '1' | 'SMO_BOARDS' | '???' 
'BP'       | 'EMPTY'  | 'G97614-002'(!) = 'YES;YES;CNC;CNC;ok;VLD' | 'G97614-002' |'CONN72_G97614002' | '(SYM_2)CONN,MISC,72P,CONNECTOR,MINISAS HD' | 'IO'  | '0.550 IN' | 'PRESSFIT'     | '0.061'     | 'http://speed.intel.com:8081/speed/module/pdm/item/pdm_item_detail_direct.asp?item_cde=G97614-002&item_rev=01&url_param=unused' | 'Design' | 'NO' | '1' | 'SMO_BOARDS' | '???' 
END_PART
END.
